# TIMECARD (Time Appliance Project (Time Card)) — schematic netlist excerpt (pin names and nets, part order shuffled) for the footprints in the layout excerpt that follows; sources: Cadence DE-HDL packaged netlist, KiCad conversion of R4006-B0001-02_R01.brd

R212  RESISTOR  100OHM 1%  pkg SMC_0402R_H016  page 10 : \1\ = FPGA_M0 ; \2\ = SG
L1  INDUCTOR_2  4.7UH 20%  pkg SMC_L_287X268_V3  page 32 : \1\ = XP5R0V_SW ; \2\ = XP5R0V

(kicad_pcb
	(version 20260206)
	(generator "pcbnew")
	(generator_version "10.0")
	(general
		(thickness 1.6)
		(legacy_teardrops no)
	)
	(paper "A4")
	(title_block
		(title "timecard-production-celestica-r4006 — R4006-B0001-02_R01.brd")
		(comment 1 "Time Appliance Project (Time Card) / footprints 49-50 of 1113")
	)
	(layers
		(0 "F.Cu" signal "TOP")
		(4 "In1.Cu" signal "L02_GND1")
		(6 "In2.Cu" signal "L03_SIG1")
		(8 "In3.Cu" signal "L04_GND2")
		(10 "In4.Cu" signal "L05_VCC1")
		(12 "In5.Cu" signal "L06_VCC2")
		(14 "In6.Cu" signal "L07_GND3")
		(16 "In7.Cu" signal "L08_SIG2")
		(18 "In8.Cu" signal "L09_GND4")
		(2 "B.Cu" signal "BOTTOM")
		(9 "F.Adhes" user "F.Adhesive")
		(11 "B.Adhes" user "B.Adhesive")
		(13 "F.Paste" user "Package Geometry/Pastemask Top")
		(15 "B.Paste" user "Package Geometry/Pastemask Bottom")
		(5 "F.SilkS" user "Ref Des/Silkscreen Top")
		(7 "B.SilkS" user "Ref Des/Silkscreen Bottom")
		(1 "F.Mask" user "Board Geometry/Soldermask Top")
		(3 "B.Mask" user "Board Geometry/Soldermask Bottom")
		(17 "Dwgs.User" user "User.Drawings")
		(19 "Cmts.User" user "User.Comments")
		(21 "Eco1.User" user "User.Eco1")
		(23 "Eco2.User" user "User.Eco2")
		(25 "Edge.Cuts" user "Board Geometry/Outline")
		(27 "Margin" user)
		(31 "F.CrtYd" user "Package Geometry/Place Bound Top")
		(29 "B.CrtYd" user "Package Geometry/Place Bound Bottom")
		(35 "F.Fab" user "Ref Des/Assembly Top")
		(33 "B.Fab" user "Ref Des/Assembly Bottom")
	)
	(footprint ""
		(layer "F.Cu")
		(at 124.587 -43.688)
		(property "Reference" "R212"
			(at 3.048 -1.35763 0)
			(unlocked yes)
			(layer "F.SilkS")
			(effects
				(font
					(size 0.7874 0.5842)
					(thickness 0.1524)
				)
			)
		)
		(property "Value" "VAL*"
			(at 0.02032 2.13233 0)
			(unlocked yes)
			(layer "F.Fab")
			(hide yes)
			(effects
				(font
					(size 0.7874 0.5842)
					(thickness 0.1524)
				)
			)
		)
		(property "Device Type" "RESISTOR-G155-11000-01,100OHM,A"
			(at 0.008382 1.210564 0)
			(unlocked yes)
			(layer "F.Fab")
			(hide yes)
			(effects
				(font
					(size 0.7874 0.5842)
					(thickness 0.1524)
				)
			)
		)
		(property "User Part Number" "PARTNUM*"
			(at 0.02032 4.024884 0)
			(unlocked yes)
			(layer "Cmts.User")
			(hide yes)
			(effects
				(font
					(size 0.7874 0.5842)
					(thickness 0.1524)
				)
			)
		)
		(property "Tolerance" "TOL*"
			(at 0.044704 3.05435 0)
			(unlocked yes)
			(layer "Cmts.User")
			(hide yes)
			(effects
				(font
					(size 0.7874 0.5842)
					(thickness 0.1524)
				)
			)
		)
		(duplicate_pad_numbers_are_jumpers no)
		(fp_line
			(start -1.143 -0.5588)
			(end -1.143 0.5588)
			(stroke
				(width 0.1)
				(type default)
			)
			(layer "F.SilkS")
		)
		(fp_line
			(start -1.143 0.5588)
			(end 1.143 0.5588)
			(stroke
				(width 0.1)
				(type default)
			)
			(layer "F.SilkS")
		)
		(fp_line
			(start 1.143 -0.5588)
			(end -1.143 -0.5588)
			(stroke
				(width 0.1)
				(type default)
			)
			(layer "F.SilkS")
		)
		(fp_line
			(start 1.143 0.5588)
			(end 1.143 -0.5588)
			(stroke
				(width 0.1)
				(type default)
			)
			(layer "F.SilkS")
		)
		(fp_rect
			(start -1.143 0.5588)
			(end 1.143 -0.5588)
			(stroke
				(width 0)
				(type default)
			)
			(fill no)
			(layer "F.CrtYd")
		)
		(fp_line
			(start -0.508 -0.3048)
			(end -0.508 0.3048)
			(stroke
				(width 0.1)
				(type default)
			)
			(layer "F.Fab")
		)
		(fp_line
			(start -0.508 0.3048)
			(end 0.508 0.3048)
			(stroke
				(width 0.1)
				(type default)
			)
			(layer "F.Fab")
		)
		(fp_line
			(start 0.508 -0.3048)
			(end -0.508 -0.3048)
			(stroke
				(width 0.1)
				(type default)
			)
			(layer "F.Fab")
		)
		(fp_line
			(start 0.508 0.3048)
			(end 0.508 -0.3048)
			(stroke
				(width 0.1)
				(type default)
			)
			(layer "F.Fab")
		)
		(pad "1" smd rect
			(at -0.5334 0)
			(size 0.7112 0.6096)
			(layers "F.Cu" "F.Mask" "F.Paste")
			(net "FPGA_M0")
		)
		(pad "2" smd rect
			(at 0.5334 0)
			(size 0.7112 0.6096)
			(layers "F.Cu" "F.Mask" "F.Paste")
			(net "SG")
		)
		(zone
			(layer "F.Cu")
			(hatch none 0.5)
			(connect_pads
				(clearance 0)
			)
			(min_thickness 0.25)
			(keepout
				(tracks allowed)
				(vias not_allowed)
				(pads allowed)
				(copperpour not_allowed)
				(footprints allowed)
			)
			(placement
				(enabled no)
				(sheetname "")
			)
			(fill
				(thermal_gap 0.5)
				(thermal_bridge_width 0.5)
				(island_removal_mode 0)
			)
			(polygon
				(pts
					(xy 124.5108 -43.3832) (xy 124.6632 -43.3832) (xy 124.6632 -43.9928) (xy 124.5108 -43.9928)
				)
			)
		)
	)
	(footprint ""
		(layer "F.Cu")
		(at 49.8094 -100.9904)
		(property "Reference" "L1"
			(at 0.1016 4.63677 0)
			(unlocked yes)
			(layer "F.SilkS")
			(effects
				(font
					(size 0.7874 0.5842)
					(thickness 0.1524)
				)
			)
		)
		(property "Value" "VAL*"
			(at -0.035306 8.510778 0)
			(unlocked yes)
			(layer "F.Fab")
			(hide yes)
			(effects
				(font
					(size 0.7874 0.5842)
					(thickness 0.1524)
				)
			)
		)
		(property "Tolerance" "TOL*"
			(at -0.061722 7.222744 0)
			(unlocked yes)
			(layer "Cmts.User")
			(hide yes)
			(effects
				(font
					(size 0.7874 0.5842)
					(thickness 0.1524)
				)
			)
		)
		(property "User Part Number" "PARTNUM*"
			(at 0 6.106668 0)
			(unlocked yes)
			(layer "Cmts.User")
			(hide yes)
			(effects
				(font
					(size 0.7874 0.5842)
					(thickness 0.1524)
				)
			)
		)
		(property "Device Type" "INDUCTOR_2-G190-10424-01,4.7UHA"
			(at 0 4.912868 0)
			(unlocked yes)
			(layer "F.Fab")
			(hide yes)
			(effects
				(font
					(size 0.7874 0.5842)
					(thickness 0.1524)
				)
			)
		)
		(duplicate_pad_numbers_are_jumpers no)
		(fp_line
			(start -4.448302 -3.803904)
			(end 4.448302 -3.803904)
			(stroke
				(width 0.1)
				(type default)
			)
			(layer "F.SilkS")
		)
		(fp_line
			(start -4.448302 3.803904)
			(end -4.448302 -3.803904)
			(stroke
				(width 0.1)
				(type default)
			)
			(layer "F.SilkS")
		)
		(fp_line
			(start 4.448302 -3.803904)
			(end 4.448302 3.803904)
			(stroke
				(width 0.1)
				(type default)
			)
			(layer "F.SilkS")
		)
		(fp_line
			(start 4.448302 3.803904)
			(end -4.448302 3.803904)
			(stroke
				(width 0.1)
				(type default)
			)
			(layer "F.SilkS")
		)
		(fp_rect
			(start 4.702302 -4.057904)
			(end -4.702302 4.057904)
			(stroke
				(width 0)
				(type default)
			)
			(fill no)
			(layer "F.CrtYd")
		)
		(fp_line
			(start -3.800094 -3.549904)
			(end 3.800094 -3.549904)
			(stroke
				(width 0.1)
				(type default)
			)
			(layer "F.Fab")
		)
		(fp_line
			(start -3.800094 3.549904)
			(end -3.800094 -3.549904)
			(stroke
				(width 0.1)
				(type default)
			)
			(layer "F.Fab")
		)
		(fp_line
			(start 3.800094 -3.549904)
			(end 3.800094 3.549904)
			(stroke
				(width 0.1)
				(type default)
			)
			(layer "F.Fab")
		)
		(fp_line
			(start 3.800094 3.549904)
			(end -3.800094 3.549904)
			(stroke
				(width 0.1)
				(type default)
			)
			(layer "F.Fab")
		)
		(fp_text user "1"
			(at -3.7084 4.50977 0)
			(unlocked yes)
			(layer "F.SilkS")
			(effects
				(font
					(size 0.7874 0.5842)
					(thickness 0.1524)
				)
			)
		)
		(fp_text user "2"
			(at 4.0386 4.50977 0)
			(unlocked yes)
			(layer "F.SilkS")
			(effects
				(font
					(size 0.7874 0.5842)
					(thickness 0.1524)
				)
			)
		)
		(fp_text user "1"
			(at -4.3434 0.30607 0)
			(unlocked yes)
			(layer "F.Fab")
			(effects
				(font
					(size 0.7874 0.5842)
					(thickness 0.1524)
				)
			)
		)
		(fp_text user "2"
			(at 4.5466 0.05207 0)
			(unlocked yes)
			(layer "F.Fab")
			(effects
				(font
					(size 0.7874 0.5842)
					(thickness 0.1524)
				)
			)
		)
		(pad "1" smd rect
			(at -2.975102 0)
			(size 2.4384 3.7084)
			(layers "F.Cu" "F.Mask" "F.Paste")
			(net "XP5R0V_SW")
		)
		(pad "2" smd rect
			(at 2.975102 0)
			(size 2.4384 3.7084)
			(layers "F.Cu" "F.Mask" "F.Paste")
			(net "XP5R0V")
		)
		(zone
			(layer "F.Cu")
			(hatch none 0.5)
			(connect_pads
				(clearance 0)
			)
			(min_thickness 0.25)
			(keepout
				(tracks allowed)
				(vias not_allowed)
				(pads allowed)
				(copperpour not_allowed)
				(footprints allowed)
			)
			(placement
				(enabled no)
				(sheetname "")
			)
			(fill
				(thermal_gap 0.5)
				(thermal_bridge_width 0.5)
				(island_removal_mode 0)
			)
			(polygon
				(pts
					(xy 46.009306 -97.440496) (xy 46.009306 -99.1362) (xy 48.053498 -99.1362) (xy 48.053498 -102.8446)
					(xy 46.009306 -102.8446) (xy 46.009306 -104.540304) (xy 53.609494 -104.540304) (xy 53.609494 -102.8446)
					(xy 51.565302 -102.8446) (xy 51.565302 -99.1362) (xy 53.609494 -99.1362) (xy 53.609494 -97.440496)
				)
			)
		)
	)
)
